# SCM (Grand Teton) — schematic netlist excerpt (pin names and nets, part order shuffled) for the footprints in the layout excerpt that follows; sources: Cadence DE-HDL packaged netlist, KiCad conversion of 12092022_DA0F0TMDCD0_F0T_Management_Board_D_brd_V3_OCP.brd

U21  IDTQS3VH257PAG  IC  pkg SMLF  page 44
  S  = FM_BMC_BIOS_MUX_CS_SPI_R_SEL_0
  I_0A  = SPI_SYS_MUX_WP_IO2
  I_1A  = SPI_BMC_BIOS_ROM_R_IO2
  YA  = SPI_PCH_MUXED_IO2
  I_0B  = SPI_SYS_MUX_MISO
  I_1B  = SPI_BMC_BIOS_ROM_R_MISO
  YB  = SPI_PCH_MUXED_IO1
  GND  = GND
  YC  = SPI_PCH_MUXED_CS0_N
  I_1C  = SPI_BMC_BIOS_SOURCE_CS0_N
  I_0C  = SPI_PCH_SECURE_CS0_N
  YD  = TP_BIOS_MUX1_PIN12
  I_1D  = TP_BIOS_MUX1_PIN13
  I_0D  = TP_BIOS_MUX1_PIN14
  \e*\  = PD_BIOS_MUX_EN_N
  VCC  = P3V3_AUX

(kicad_pcb
	(version 20260206)
	(generator "pcbnew")
	(generator_version "10.0")
	(general
		(thickness 1.6)
		(legacy_teardrops no)
	)
	(paper "A4")
	(title_block
		(title "12092022_DA0F0TMDCD0_F0T_Management_Board_D_brd_V3_OCP.brd")
		(comment 1 "Grand Teton / footprints 961-961 of 1440")
	)
	(layers
		(0 "F.Cu" signal "TOP")
		(4 "In1.Cu" signal "GND")
		(6 "In2.Cu" signal "IN1")
		(8 "In3.Cu" signal "GND1")
		(10 "In4.Cu" signal "IN2")
		(12 "In5.Cu" signal "VCC")
		(14 "In6.Cu" signal "VCC1")
		(16 "In7.Cu" signal "IN3")
		(18 "In8.Cu" signal "GND2")
		(20 "In9.Cu" signal "IN4")
		(22 "In10.Cu" signal "GND3")
		(2 "B.Cu" signal "BOTTOM")
		(9 "F.Adhes" user "F.Adhesive")
		(11 "B.Adhes" user "B.Adhesive")
		(13 "F.Paste" user "Package Geometry/Pastemask Top")
		(15 "B.Paste" user "Package Geometry/Pastemask Bottom")
		(5 "F.SilkS" user "Ref Des/Silkscreen Top")
		(7 "B.SilkS" user "Ref Des/Silkscreen Bottom")
		(1 "F.Mask" user "Board Geometry/Soldermask Top")
		(3 "B.Mask" user "Board Geometry/Soldermask Bottom")
		(17 "Dwgs.User" user "User.Drawings")
		(19 "Cmts.User" user "User.Comments")
		(21 "Eco1.User" user "User.Eco1")
		(23 "Eco2.User" user "User.Eco2")
		(25 "Edge.Cuts" user "Board Geometry/Outline")
		(27 "Margin" user)
		(31 "F.CrtYd" user "Package Geometry/Place Bound Top")
		(29 "B.CrtYd" user "Package Geometry/Place Bound Bottom")
		(35 "F.Fab" user "Ref Des/Assembly Top")
		(33 "B.Fab" user "Ref Des/Assembly Bottom")
	)
	(footprint ""
		(layer "B.Cu")
		(at 43.890184 -101.70287)
		(property "Reference" "U21"
			(at 0.369316 3.44424 0)
			(unlocked yes)
			(layer "B.SilkS")
			(effects
				(font
					(size 0.7874 0.5842)
					(thickness 0.1524)
				)
				(justify left mirror)
			)
		)
		(property "Value" ""
			(at 0 0 0)
			(layer "B.Fab")
			(effects
				(font
					(size 1.27 1.27)
				)
				(justify mirror)
			)
		)
		(duplicate_pad_numbers_are_jumpers no)
		(fp_line
			(start -2.0066 -2.5654)
			(end -2.0066 2.5654)
			(stroke
				(width 0.1524)
				(type default)
			)
			(layer "B.SilkS")
		)
		(fp_line
			(start -2.0066 2.5654)
			(end 2.0066 2.5654)
			(stroke
				(width 0.1524)
				(type default)
			)
			(layer "B.SilkS")
		)
		(fp_line
			(start -0.5842 -2.5654)
			(end -2.0066 -2.5654)
			(stroke
				(width 0.1524)
				(type default)
			)
			(layer "B.SilkS")
		)
		(fp_line
			(start 0 -1.9812)
			(end -0.5842 -2.5654)
			(stroke
				(width 0.1524)
				(type default)
			)
			(layer "B.SilkS")
		)
		(fp_line
			(start 0.5842 -2.5654)
			(end 0 -1.9812)
			(stroke
				(width 0.1524)
				(type default)
			)
			(layer "B.SilkS")
		)
		(fp_line
			(start 2.0066 -2.5654)
			(end 0.5842 -2.5654)
			(stroke
				(width 0.1524)
				(type default)
			)
			(layer "B.SilkS")
		)
		(fp_line
			(start 2.0066 2.5654)
			(end 2.0066 -2.5654)
			(stroke
				(width 0.1524)
				(type default)
			)
			(layer "B.SilkS")
		)
		(fp_poly
			(pts
				(xy 3.853688 -2.300478) (xy 4.869688 -2.808478) (xy 4.869688 -1.792478)
			)
			(stroke
				(width 0)
				(type default)
			)
			(fill yes)
			(layer "B.SilkS")
		)
		(fp_line
			(start -3.7338 -2.5654)
			(end -3.6703 -2.5654)
			(stroke
				(width 0.1)
				(type default)
			)
			(layer "B.Fab")
		)
		(fp_line
			(start -3.7338 2.5654)
			(end -3.7338 -2.5654)
			(stroke
				(width 0.1)
				(type default)
			)
			(layer "B.Fab")
		)
		(fp_line
			(start -3.6703 -2.5654)
			(end 3.6703 -2.5654)
			(stroke
				(width 0.1)
				(type default)
			)
			(layer "B.Fab")
		)
		(fp_line
			(start -3.6703 2.5654)
			(end -3.7338 2.5654)
			(stroke
				(width 0.1)
				(type default)
			)
			(layer "B.Fab")
		)
		(fp_line
			(start 3.6703 -2.5654)
			(end 3.7338 -2.5654)
			(stroke
				(width 0.1)
				(type default)
			)
			(layer "B.Fab")
		)
		(fp_line
			(start 3.6703 2.5654)
			(end -3.6703 2.5654)
			(stroke
				(width 0.1)
				(type default)
			)
			(layer "B.Fab")
		)
		(fp_line
			(start 3.7338 -2.5654)
			(end 3.7338 2.5654)
			(stroke
				(width 0.1)
				(type default)
			)
			(layer "B.Fab")
		)
		(fp_line
			(start 3.7338 2.5654)
			(end 3.6703 2.5654)
			(stroke
				(width 0.1)
				(type default)
			)
			(layer "B.Fab")
		)
		(fp_poly
			(pts
				(xy 3.955288 -2.275078) (xy 4.971288 -2.783078) (xy 4.971288 -1.767078)
			)
			(stroke
				(width 0)
				(type default)
			)
			(fill yes)
			(layer "B.Fab")
		)
		(pad "1" smd rect
			(at 2.921 -2.275078 270)
			(size 0.3556 1.4986)
			(layers "B.Cu" "B.Mask" "B.Paste")
			(net "FM_BMC_BIOS_MUX_CS_SPI_R_SEL_0")
		)
		(pad "2" smd rect
			(at 2.921 -1.625092 270)
			(size 0.3556 1.4986)
			(layers "B.Cu" "B.Mask" "B.Paste")
			(net "SPI_SYS_MUX_WP_IO2")
		)
		(pad "3" smd rect
			(at 2.921 -0.975106 270)
			(size 0.3556 1.4986)
			(layers "B.Cu" "B.Mask" "B.Paste")
			(net "SPI_BMC_BIOS_ROM_R_IO2")
		)
		(pad "4" smd rect
			(at 2.921 -0.32512 270)
			(size 0.3556 1.4986)
			(layers "B.Cu" "B.Mask" "B.Paste")
			(net "SPI_PCH_MUXED_IO2")
		)
		(pad "5" smd rect
			(at 2.921 0.32512 270)
			(size 0.3556 1.4986)
			(layers "B.Cu" "B.Mask" "B.Paste")
			(net "SPI_SYS_MUX_MISO")
		)
		(pad "6" smd rect
			(at 2.921 0.975106 270)
			(size 0.3556 1.4986)
			(layers "B.Cu" "B.Mask" "B.Paste")
			(net "SPI_BMC_BIOS_ROM_R_MISO")
		)
		(pad "7" smd rect
			(at 2.921 1.625092 270)
			(size 0.3556 1.4986)
			(layers "B.Cu" "B.Mask" "B.Paste")
			(net "SPI_PCH_MUXED_IO1")
		)
		(pad "8" smd rect
			(at 2.921 2.275078 270)
			(size 0.3556 1.4986)
			(layers "B.Cu" "B.Mask" "B.Paste")
			(net "GND")
		)
		(pad "9" smd rect
			(at -2.921 2.275078 270)
			(size 0.3556 1.4986)
			(layers "B.Cu" "B.Mask" "B.Paste")
			(net "SPI_PCH_MUXED_CS0_N")
		)
		(pad "10" smd rect
			(at -2.921 1.625092 270)
			(size 0.3556 1.4986)
			(layers "B.Cu" "B.Mask" "B.Paste")
			(net "SPI_BMC_BIOS_SOURCE_CS0_N")
		)
		(pad "11" smd rect
			(at -2.921 0.975106 270)
			(size 0.3556 1.4986)
			(layers "B.Cu" "B.Mask" "B.Paste")
			(net "SPI_PCH_SECURE_CS0_N")
		)
		(pad "12" smd rect
			(at -2.921 0.32512 270)
			(size 0.3556 1.4986)
			(layers "B.Cu" "B.Mask" "B.Paste")
			(net "TP_BIOS_MUX1_PIN12")
		)
		(pad "13" smd rect
			(at -2.921 -0.32512 270)
			(size 0.3556 1.4986)
			(layers "B.Cu" "B.Mask" "B.Paste")
			(net "TP_BIOS_MUX1_PIN13")
		)
		(pad "14" smd rect
			(at -2.921 -0.975106 270)
			(size 0.3556 1.4986)
			(layers "B.Cu" "B.Mask" "B.Paste")
			(net "TP_BIOS_MUX1_PIN14")
		)
		(pad "15" smd rect
			(at -2.921 -1.625092 270)
			(size 0.3556 1.4986)
			(layers "B.Cu" "B.Mask" "B.Paste")
			(net "PD_BIOS_MUX_EN_N")
		)
		(pad "16" smd rect
			(at -2.921 -2.275078 270)
			(size 0.3556 1.4986)
			(layers "B.Cu" "B.Mask" "B.Paste")
			(net "P3V3_AUX")
		)
	)
)
